FILE_TYPE = MACRO_DRAWING;
SET COLOR_WIRE YELLOW;
SET COLOR_PROP MONO;
SET COLOR_DOT WHITE;
SET COLOR_ARC YELLOW;
SET COLOR_BODY GREEN;
SET COLOR_NOTE MONO;
SET PROP_DISPLAY VALUE;
SET PAGE_NUMBER P11;
FORCEADD INTEL_CORP_BPAGE..1
(4250 200);
FORCEPROP 1 LAST CDS_CON_LAST_MODIFIED Fri Jun 16 17:48:01 2017
J 0
(2825 525);
PAINT ORANGE (2825 525);
DISPLAY INVISIBLE (2825 525);
FORCEPROP 1 LAST CUSTOM_TXT_CDS <CURRENT_DESIGN_SHEET> OF <TOTAL_DESIGN_SHEETS>
J 0
(3750 225);
PAINT ORANGE (3750 225);
FORCEPROP 1 LAST CUSTOM_TXT_CDS <CON_LAST_MODIFIED>
J 0
(250 300);
PAINT ORANGE (250 300);
FORCEPROP 2 LAST CUSTOM_TXT_CDS <XR_PAGE_TITLE>
J 0
(-3640 5450);
DISPLAY 0.638298 (-3640 5450);
PAINT PINK (-3640 5450);
DISPLAY INVISIBLE (-3640 5450);
FORCEPROP 1 LAST SCH_TITLE FAN BLOCK DIAGRAM
J 0
(-3700 250);
DISPLAY 1.212766 (-3700 250);
PAINT ORANGE (-3700 250);
FORCEPROP 2 LAST CDS_LIB mstr_symbols
J 0
(4250 200);
PAINT MONO (4250 200);
DISPLAY INVISIBLE (4250 200);
FORCEPROP 2 LAST PAGE_BORDER TRUE
J 0
(-3640 5450);
DISPLAY 0.638298 (-3640 5450);
PAINT PINK (-3640 5450);
DISPLAY INVISIBLE (-3640 5450);
FORCEPROP 1 LAST COMMENT_BODY TRUE
J 0
(4262 212);
DISPLAY 0.468085 (4262 212);
PAINT GREEN (4262 212);
DISPLAY INVISIBLE (4262 212);
FORCEPROP 2 LAST CDS_XR_PAGE_TITLE CR-11 : @BASEBOARD_FAB2_LIB.BASEBOARD_FAB2(SCH_1):PAGE11
J 0
(-3640 5450);
DISPLAY 0.638298 (-3640 5450);
PAINT PINK (-3640 5450);
DISPLAY INVISIBLE (-3640 5450);
FORCENOTE
$CDS_IMAGE|FAN and PUMP block diagram_20161005.jpg|6295|5250
(375 2725) 0;
DISPLAY LEFT (375 2725);
QUIT
